M48
INCH,TZ
T01C.008
T02C.01
T03C.012
T04C.014
T05C.01417
T06C.01456
T07C.016
T08C.02
T09C.02913
T10C.062
T11C.083
T12C.138
T13C.146
T14C.042
T15C.086
T16C.087
T17C.094
T18C.097
T19C.119
;LEADER: 12 
;HEADER: 
;CODE  : ASCII 
;FILE  : 16316-1-1-8.drl for board 16316-1.brd ... layers TOP and BOTTOM
;T01 Holesize 1. = 8.000000 Tolerance = +0.000000/-0.000000 PLATED MILS Quantity = 711
;T02 Holesize 2. = 10.000000 Tolerance = +0.000000/-0.000000 PLATED MILS Quantity = 1377
;T03 Holesize 3. = 12.000000 Tolerance = +0.000000/-0.000000 PLATED MILS Quantity = 67
;T04 Holesize 4. = 14.000000 Tolerance = +0.000000/-0.000000 PLATED MILS Quantity = 26
;T05 Holesize 5. = 14.170000 Tolerance = +0.000000/-0.000000 PLATED MILS Quantity = 418
;T06 Holesize 6. = 14.560000 Tolerance = +0.000000/-0.000000 PLATED MILS Quantity = 36
;T07 Holesize 7. = 16.000000 Tolerance = +0.000000/-0.000000 PLATED MILS Quantity = 830
;T08 Holesize 8. = 20.000000 Tolerance = +0.000000/-0.000000 PLATED MILS Quantity = 19
;T09 Holesize 9. = 29.130000 Tolerance = +0.000000/-0.000000 PLATED MILS Quantity = 12
;T10 Holesize 10. = 62.000000 Tolerance = +0.000000/-0.000000 PLATED MILS Quantity = 2
;T11 Holesize 11. = 83.000000 Tolerance = +0.000000/-0.000000 PLATED MILS Quantity = 2
;T12 Holesize 12. = 138.000000 Tolerance = +0.000000/-0.000000 PLATED MILS Quantity = 2
;T13 Holesize 13. = 146.000000 Tolerance = +0.000000/-0.000000 PLATED MILS Quantity = 2
;T14 Holesize 14. = 42.000000 Tolerance = +0.000000/-0.000000 NON_PLATED MILS Quantity = 2
;T15 Holesize 15. = 86.000000 Tolerance = +0.000000/-0.000000 NON_PLATED MILS Quantity = 6
;T16 Holesize 16. = 87.000000 Tolerance = +0.000000/-0.000000 NON_PLATED MILS Quantity = 2
;T17 Holesize 17. = 94.000000 Tolerance = +0.000000/-0.000000 NON_PLATED MILS Quantity = 1
;T18 Holesize 18. = 97.000000 Tolerance = +0.000000/-0.000000 NON_PLATED MILS Quantity = 1
;T19 Holesize 19. = 119.000000 Tolerance = +0.000000/-0.000000 NON_PLATED MILS Quantity = 4
%
G90
T01
X374432Y316002
X389764Y251969
X389000Y236100
X389764Y228347
Y220473
Y216536
Y212599
Y208662
Y204725
X397638Y200788
X393701
Y204725
X397638
Y208662
X393701
X397638Y212599
X393701
X397638Y216536
X393701
Y220473
X397638
Y224410
X393701Y228347
X397638
Y232284
Y236221
Y240158
Y244095
Y251969
X393701
X397638Y259843
Y271654
Y279528
Y287402
Y295276
Y303150
Y311024
Y318898
Y326772
X409449
Y318898
Y314961
Y311024
X405512Y303150
Y295276
Y287402
X409449Y275591
Y267717
Y259843
X405512
X409449Y255906
X405512
X401575Y248032
X409449
X405512
X409449Y244095
X401575
X405512
X401575Y240158
X409449
X405512
Y236221
X409449
X401575
X405512Y232284
X401575
X409449
X401727Y228641
X405512Y228347
X409449Y224410
X401575Y220473
X409449
X405512
Y216536
X401575
X409449
X401575Y212599
X409449
X405512
X401575Y208662
X409449
X405512
X401575Y204725
X405512
X409449
X405512Y200788
X401575
X409449
X413386
X417323
X413386Y204725
X417323
X413386Y208662
X417323
Y212599
X413386
Y216536
X417323
X413386Y220473
X417323
X413386Y224410
X417323
X413386Y232284
X417322Y236221
X417323Y240157
X413387Y240158
X413386Y244095
X417323
Y248032
X413386
X417323Y251969
X413386
X417323Y255906
X413386
Y259843
X417323
Y267717
Y275591
Y299213
Y303150
Y307087
X413386
Y311025
X417323Y311024
Y314961
X413386Y314962
X417323Y318898
X417322Y322835
X413386Y326772
X417323
X421260
X421259Y322835
X429134Y318898
X425197
X421260
X425197Y314961
X421260
X429134
X425197Y311024
X429134
X421260Y307088
X425197Y307087
Y303150
X429134Y303151
X421260
X425197Y299213
X429134Y299214
X421260
Y295277
X429134
X425197Y295276
Y291339
X421260
X429134Y291340
X425197Y287402
X429134Y287403
X425196Y283466
X429134Y279528
X421260
X429134Y271654
Y263781
X421260Y259843
X425197
X421260Y255906
X429134
X425197
X429134Y251969
X421260
Y248032
X429134
X421260Y244095
X421259Y240158
X425196
X425197Y236220
X421258Y232283
X425196Y228347
X425197Y224410
X421260Y220473
X425197
X429134
Y216536
X425197
X421260
X429134Y212599
X425197
X421260
X425197Y208662
X421260
X429134
X425197Y204725
X429134
X421260
X429134Y200788
X421260
X425197
X433071
X437008
X433071Y204725
X437008
Y208662
X433071
Y212599
X437008
X433071Y216536
X437008
X433071Y220473
X437008
X433071Y224410
X433070Y228347
Y232284
Y236221
X433071Y240158
Y244095
Y248032
X433070Y255905
X437007
Y259843
X433071Y263781
X437007Y267718
X437008Y275591
X433071
X437057Y279414
X433070Y279528
X433071Y283465
X433070Y287402
X437007
X437008Y291339
X433071
X437008Y295276
X433071
X437008Y299213
X433071
X437008Y303150
X433071
Y307087
X437008
Y311024
X433071
X437008Y314961
X433071
Y318898
X437008
X438976Y327204
X431102Y331263
X442800Y330300
X446200Y327400
X442913Y327204
X440944Y322835
X444881
X440945Y318898
X444882
X448819
Y314961
X440945
X444882
X440945Y311024
X448818
X440945Y307087
X448819Y307088
X440945Y303150
X448818Y303151
Y299214
X444882Y299213
X440945
X448818Y295276
X440945
X448818Y291339
X440945
X448819Y287403
X444882Y287402
X440945
Y283465
X448819
X444882Y279529
Y275591
X448818Y271655
X440944
Y267718
X448818
Y263780
X440944
Y259843
X448818
X440944Y255906
X448818
X440945Y248032
X448819
X440945Y244095
X448819
X440945Y240158
X448819
X448818Y236221
X440944
Y232284
X448818
X440944Y228347
X448818
X448819Y224410
X440945
X448819Y220473
X444882
X440945
X444882Y216536
X448819
X440945
X444882Y212599
X440945
X448819
Y208662
X444882
X440945
Y204725
X444882
X448819
Y200788
X444882
X440945
X456693
Y204725
Y208662
Y212599
Y216536
Y220473
Y224410
Y228347
Y232284
Y236221
Y240158
Y244095
Y248032
Y255906
Y259843
Y263780
Y267718
Y271655
X452756Y275592
X456693Y279528
X452757Y279529
X456693Y287402
X452755
Y291340
X456693Y291339
X456694Y295276
X452755Y295277
X456693Y299213
X452755Y303150
X456693
X452755Y307087
X456693
Y311024
Y314961
Y318898
X462599Y327204
X460630Y318898
X464567
X468504
X460630Y314961
X468504
X464567Y311025
X460630Y311024
X468504
X464567Y307088
X460630Y307087
X468505Y307088
X460630Y303150
X464567Y303151
X468504
Y299214
X460630Y299213
X464567Y299214
X460631Y295277
X460630Y291339
X464568Y287402
X468505
X460630Y283465
X468504
X464567Y279529
X464568Y275592
X460630
X464567Y271655
Y267718
Y263780
Y259843
Y255906
Y248032
Y244095
Y240158
Y236221
Y232284
Y228347
Y224410
X460630Y220473
X468504
X464567
X468504Y216536
X460630
X464567
Y212599
X460630
X468504
X460630Y208662
X468504
X464567
Y204725
X468504
X460630
X464567Y200788
X468504
X460630
X472441
X476378
Y204725
X472441
Y208662
X476378
Y212599
X472441
X476378Y216536
X472441
Y220473
X476378
X472441Y224410
Y228347
Y232284
Y236221
Y240158
Y244095
Y251969
X476378
Y259843
X472441
Y267717
X476378
X472441Y275591
X476378
X472441Y283465
X472442Y287402
X476379
X476378Y291339
X472441
Y295276
Y299213
Y303150
Y307087
X476378Y311024
X472441Y314961
X476378
X472441Y318898
X476378
X470473Y327204
X488189Y322835
X484252Y318898
Y314961
X488189Y311024
X484252Y307087
X488189
X480315Y303150
X484252
X488189
X480315Y299213
X488189
X480315Y295276
X488189
X484252Y295277
X488189Y291339
X484252Y291340
X480315Y291339
X488189Y287402
X484252
X480316Y287403
X480315Y283465
X488189
X480315Y279528
X484252
X488189
X480315Y275591
X488189
X484252Y271654
X480315
X488189
Y267717
X480315
X484252Y259843
X488189
X480315
X488189Y255906
X480315
X484252Y251969
X480315
Y248032
X488189
X480315Y244095
X484252
X480315Y240158
X488189
X484252Y236221
X488189Y232284
X480315
Y228347
X488189Y224410
X480315
X488189Y220473
X480315
X484252
X488189Y216536
X484252
X480315
Y212599
X488189
X484252
X488189Y208662
X484252
X480315
X488189Y204725
X484252
X480315
X488189Y200788
X480315
X484252
X492126
Y204725
Y208662
X496063
Y212599
X492126
Y216536
X496063
Y220473
X492126
X496063Y224410
X492126
X496063Y228347
Y232284
X492126
Y236221
X496063
Y240158
X492126
Y244095
X496063
X492126Y248032
X496063
Y251969
X492126
X496063Y255906
Y259843
X492126
X496063Y267717
X492126
X496063Y271654
X492126
Y275591
X496063
Y279528
X492126
X496063Y283465
X492126
Y287402
X496063
Y291339
X492126
X496063Y295276
Y299213
X492126Y303150
X496063
Y307087
X492126
X496063Y311024
X492126
Y314961
X496063
X492126Y318898
X496063
X503937
X500000
X507874
Y314961
X500001
X507874Y311024
X500000Y311025
X503937Y311024
X507874Y307087
X500000Y307088
X503937Y307087
X500000Y303150
X507874
X503937
Y299213
X500000
X503937Y295276
X507874
X500000
Y291339
X503937
X500000Y287402
X503937
X507874
X503937Y283465
X507874
X500000
X507874Y279528
X503937
X500000
Y275591
X503937
X507874
Y271654
X500000
X503937
X507874Y267717
X500000
X503937
X500000Y259843
X507874
X503937
Y255906
X507874
X500000
X507874Y251969
X500000
X503937
Y248032
X507874
X500000
Y244095
X503937
X507874
X500000Y240158
X503937
X507874
X500000Y236221
X507874
X503937
Y232284
X500000
X507874Y228347
X503937
X500000
Y224410
X503937
X507874Y220473
X503937
X500000
X503937Y216536
X500000
X507874Y212599
X503937
X500000
X503937Y208662
X507874
X500000
X507874Y204725
X500000
X503937
Y200788
X507874
X500000
X511811
Y208662
X517000Y218500
Y226370
Y234252
X515748Y240158
X511811
X515748Y244095
X511811
X515748Y248032
X511811
X515748Y251969
X511811
Y255906
X515748
Y259843
X511811
Y267717
X515748
Y271654
X511811
Y275591
X515748
X511811Y279528
X515748
Y283465
X511811
X515748Y287402
X511811
X518647Y288943
X517500Y297218
X515748Y307087
X511811
X516500Y313000
X515748Y318898
X666928Y144880
X660630Y122834
X663779
X660629Y119685
X663779
X673228
X679527
X670078
X670079Y122835
X673229
X679528
X688974Y132281
X682675
X682678Y122835
X688977
X682677Y119685
X688976
X692126Y119686
Y122835
T02
X22550Y156750
X28455Y187767
X28749Y191548
X22150Y203550
X23800Y211200
X27500
X21910Y217500
X22250Y223500
X26150Y230850
X22750Y275450
X23100Y283200
Y287700
Y292200
X23500Y296700
X24000Y301750
X23400Y309500
X23100Y314000
Y318500
X28000Y326500
X27947Y334066
X29900Y378252
X26100Y378352
X22000
X53500Y403150
X49700Y402000
X54040Y399390
X31240Y393440
X49700Y391000
X57350Y387800
X43000Y378233
X46900
X50700
X38200Y373800
X34100
X54800Y373600
X35800Y363400
X40100
X37900Y334380
X41325Y334268
X47443Y334198
X58900Y334180
X31450Y334050
X52450Y333850
X37049Y302949
X37830Y274180
X33759
X56026Y256117
X37469Y250280
X32469
X49320
X45650
X40290Y239814
X35405Y239808
X52400Y237800
X33700Y230600
X39320Y213823
X39416Y206616
X39301Y203166
X46194Y179835
X50194
X59700Y178600
X58697Y165269
X54697
X59600Y152000
X71200Y137200
X89800Y178000
X81300Y178050
X85700Y178000
X68400Y177950
X72800Y178200
X76800
X64000Y178400
X78800Y205900
X78850Y221000
X87300Y230650
X82600Y232000
X65500Y237800
X75500
X70500
X80688Y276695
Y281695
X80896Y286695
X81000Y291700
X68300Y292200
X80600Y304600
X80700Y309400
X78700Y317400
X67800Y318000
X67700Y321500
X78600Y321700
X62325Y334068
X74150Y334250
X84025Y334468
X69143Y334598
X80600Y334580
X78171Y363195
X82171
X60400Y373600
X81300Y374000
X77200
X89895Y378426
X85795
X73100Y378700
X65500Y378800
X69300
X65375Y392835
X83232Y399956
X94488Y489888
X102850Y452650
X104900Y412200
X107582Y391266
X102679Y391150
X112638Y391197
X106709Y383400
X112023Y383013
X93695Y378426
X98295Y373793
X102395
X99266Y362988
X103266
X90238Y334391
X95245Y334043
X102400Y333900
X106500
X102300Y329100
X93884Y242333
X90800Y217900
X92300Y213900
Y209400
Y204400
Y199400
Y194900
Y190900
X145900Y136500
X145585Y132451
X164020Y101127
X155991Y110061
X152800Y113400
X158612Y126645
X172800Y141001
X162522Y331774
X208648Y328452
X196600Y306800
X197100Y298800
X207600Y292400
X204400Y288700
X204997Y280702
X207500Y278400
X180300Y175400
X195400Y147200
X195500Y142400
X184600Y137400
X198202Y135298
X196963Y122029
X201139Y121630
X200550Y111350
X191000Y110000
X182100Y105500
X234693Y57400
X223994Y63225
X238867Y63650
X220228Y63651
X233759Y64752
X234450Y73000
X229000Y95000
X222320Y277658
X225500Y278900
X219400Y279400
X228300Y280900
X222000Y310600
X235500Y320100
X231700
X218500Y320200
X214700
X230400Y326200
X218400Y326600
X212198Y328316
X230400Y329600
X218300Y330000
X230000Y336500
X233400Y336600
X237483Y339988
X230400Y348000
X237600Y390500
X268004Y424361
X255500Y423361
X263250Y423411
X259800Y423400
X266300Y412100
X256172Y409530
X256900Y380900
X261581Y370979
X261996Y365663
X257996
X266500Y364000
X241556Y340111
X253245Y329698
X246100Y329700
X245943Y326300
X253154Y326227
X261365Y324351
X265365
X269365Y320351
X249775Y320167
X253575
X242400Y289700
X242402Y286300
X248900Y282932
X242351Y282900
X259629Y281000
X268400
X245800Y279200
X266406Y277835
X262800
X266895Y100227
X245250Y98250
X241750
X261102Y77900
X248169Y74454
X255300Y72600
X255154Y69177
X242727Y63391
X257499Y55353
X261499
X267188Y55192
X242610Y53714
X250137Y36053
X270000Y29000
Y33500
Y38000
Y42500
X281700Y52285
X285500
X277514Y58068
X289161
X276700Y66700
X285361Y78015
X281761
X278039Y82185
X296280Y82574
X272937Y85862
Y90362
X292030Y90574
X283393Y92325
X280298Y95556
X283385Y100227
X287385
X295385
X291385
X279385
X292385Y108227
X296385
X270143Y276969
X292225Y288267
X299635Y288650
Y292650
X284498Y299976
X275696Y314340
X288536Y314764
X273165Y320351
X280800Y325000
X294250
X290750
X277150Y332000
X281150
X297021Y346579
X280217Y350927
X287350Y351200
Y357700
X292800Y363800
X296079Y379524
X270618Y385867
X325629Y443510
X325651Y439668
X327365Y433732
X323448Y405064
X308398Y386479
X304398
X312398
X304205Y382450
X300019Y379524
X325200Y365100
X305147Y354706
X322500Y353700
X319550Y347169
X327400Y342600
X316050Y342200
X306060Y337640
X310200Y337600
X301500Y337500
X320650Y336456
X328100Y331300
X319100Y330600
X314400Y327851
X325500Y325400
X305628Y324511
X314500Y324251
X325500Y321400
X301628Y320511
X305628
X329364Y316949
X314300Y311900
X314241Y308459
X324100Y307814
X308180Y305200
X314045Y302900
X319543Y290159
X327868Y290125
X303032Y289900
X317600Y278800
X317700Y275400
X302262Y262642
X323681Y259023
X319881
X306292Y252825
X328134Y252720
X321051Y134028
X321343Y122343
X304529Y118792
X324026Y115936
X328600Y114400
X319533Y114283
X310711Y113820
X306196Y110209
X314772Y108292
X300385Y108227
X328711Y108053
X318773Y108083
X329722Y94574
X301280Y82574
X306280
X304591Y73074
X308591
Y68928
X304591
X311182Y62800
X300311Y60800
X311182Y58692
X325378Y50351
X312840Y42398
X325378Y35351
X310065Y32397
X335722Y94574
X339049Y124238
X335994Y126119
X331649Y126111
X349911Y136954
X342000Y141600
X355500Y144500
X341913Y145049
X351723Y178499
X354143Y183439
X337157Y206052
X341757Y211056
X352047Y220590
X335701Y223995
X357546Y230354
X340280Y253765
X341998Y256700
X339500Y260400
X358096Y262268
X337500Y266050
X332000Y266336
X357996Y272841
X343100Y281300
X346900
X338650Y281350
X346500Y302500
X331026Y303354
X335882Y309823
X359200Y315800
X347750Y315850
X355200Y315800
X344000Y316000
X348600Y323900
X356550Y337200
X352396
X348596Y337250
X335400Y337400
X339000Y344700
X330000Y345800
X359400Y347200
X337600Y349600
X345700Y349773
X340375Y365944
X331765Y386535
X344000Y388500
X337592Y405027
X338000Y421000
X337900Y431200
X367450Y409955
X360000Y410000
X367350Y406455
X374250Y347600
X370250
X375148Y337184
X364050Y337200
X360050
X382600
X379148Y337184
X368050Y337200
X389559Y337103
X386159Y337080
X360300Y323900
X363400Y315800
X384341Y315377
X385887Y305222
X377324Y302844
X381396Y302610
X382000Y296500
X384300Y291100
X380400Y287400
X365996Y287265
X384600Y285600
X361996Y272841
X365996
X379000Y272600
X376633Y261543
X368714Y261134
X368610Y257299
X376633Y256851
X366169Y246591
X370669
X360710Y231897
X370570Y198219
X379415Y194608
X368558Y194540
X366460Y191794
X364169Y188366
X362260Y184360
X376306Y182715
X372517Y182362
X371124Y178760
X374915Y176442
X370061Y172433
X374616Y172378
X359969Y124510
X390550Y326820
X397000Y337000
X392959Y337099
X401700Y337350
X405783Y339318
X412381Y347149
X416822Y347133
X405921Y347159
X433500Y337500
X427500
X421500
X448300
X440300
X444200Y337600
X444100Y341000
Y345000
X430464Y347078
X426464
X441000Y347800
X435000
X448431Y348737
X444959Y352053
X445000Y422000
X448500Y424000
X452500Y423500
X457599Y419642
X473900Y371800
X474200Y367500
X467774Y362151
X462450Y358960
X467100Y357500
X476500Y347650
X468500Y347500
X464500Y347410
X460800Y337562
X456550Y337500
X468300
X452300
X464300
X476200Y334900
X479640Y334674
X460300Y333500
X452600Y332700
X472463Y329837
X503800Y382700
X496300Y378935
X489500Y371200
X502850Y368500
X506700Y367309
X489600Y367209
X485100Y366800
X494400Y363800
X490000Y363700
X499100Y363409
X485100Y363400
X506200Y363209
X498700Y359209
X493200Y358800
X506200Y358809
X502138Y348500
X506262
X498138
X481359Y347727
X490877Y189047
X500302Y188989
X490877Y185047
X500302Y184989
Y180489
X490877Y180547
X500302Y176489
X490877Y176547
X520552Y176373
X510427Y176431
X520552Y180373
X510427Y180431
Y184931
X520552Y184873
X510427Y188931
X520552Y188873
X519263Y327092
X519629Y330448
X538436Y330918
X521914Y332907
X538476Y334365
X539900Y338300
X534000Y338400
X539446Y342347
X534100Y342410
X536200Y348300
X518138Y348350
X510138Y348500
X514138
X525438Y350500
X538225Y357997
X514000Y359209
X510200Y363209
X510700Y367309
X539040Y480090
X517125Y488975
X545880Y485940
X557411Y481025
X562460Y457580
X554250Y457500
X547225Y357997
X555697Y356565
X540200Y348300
X546100
X550100
X543646Y342347
X547927Y342199
X552200Y339300
X556800
X547379Y338352
X554685Y333410
X555127Y324049
X551127
X542627
X546627
X545278Y315738
X549778
X553778
X541278
X549721Y308771
X553721
X541221
X545221
X541193Y301280
X549693
X545193
X553693
X550717Y255796
X546217
X542217
X554717
X542475Y248209
X550975
X554975
X546475
X543365Y240638
X555865
X551865
X547365
X545000Y231900
X549000
X557500
X553500
X577699Y123469
X576868Y127381
X575932Y131783
X588901Y134308
X575101Y135695
X588070Y138220
X587134Y142622
X596233Y145667
X586303Y146534
X595402Y149579
X594466Y153981
X586912Y154495
X593635Y157893
X586081Y158407
X585145Y162809
X584314Y166721
X590537Y170119
X589706Y174031
X588770Y178433
X581716Y178947
X587939Y182345
X580885Y182859
X579949Y187261
X579118Y191173
X585841Y194571
X585010Y198483
X584074Y202885
X583243Y206797
X589966Y210195
X589135Y214107
X588199Y218509
X587368Y222421
X598600Y247800
Y253100
X594025Y280017
Y284017
X594050Y301755
X597450Y320750
X590350Y323011
X597450Y324750
X590200Y334350
X590050Y337950
X594400Y353000
Y357000
X594292Y362291
X598152Y370130
X589391Y378202
X598023Y383081
X589394Y384572
X594200Y390400
Y395200
X584280Y424030
X587890Y426720
X588030Y430795
X599900Y438300
X585420Y456480
X588663Y460037
X577300Y460300
X577330Y464430
X574250Y466900
X588400Y469450
X581020Y471890
X574667Y479799
X581250Y480550
X617000Y468700
X626300Y464900
X620600Y458500
X629400Y414324
X604832Y395220
X627020Y393364
X620260Y389940
X627140Y381353
X624200Y372500
X629770Y369320
X625000Y361700
X623063Y357337
X612300Y356850
X602649Y349033
X629250Y348900
Y344900
X610750Y336850
X618300Y327654
X603650Y315500
X608500Y315000
X626405Y314991
X629250Y310491
Y306491
X618300Y288745
X629900Y252000
Y245800
Y239700
X622400Y216750
X628363Y209944
X624363
X627455Y185364
X618400Y173443
X618250Y162081
X617600Y134400
X627500Y64500
X629500Y61500
X627603Y43523
X626786Y31227
X629813Y27661
X627500Y19339
X638103Y13100
X643103Y13803
X647103Y13964
X656300Y20100
X656450Y28000
X643816Y31573
X632416Y31609
X647216Y31601
X640416Y31609
X655914Y39932
X652551Y40716
X640144Y40969
X631864Y51848
X651564Y52638
X644500Y65759
X641003Y68809
X637003
X648207Y70750
X654037Y87208
Y91208
Y94708
X635942Y97351
X646643Y97859
X654037Y98708
X630600Y102000
X634400
X640600Y111600
X644100Y111811
X654330Y113385
X657480
X657479Y116536
X654330Y116535
Y119685
Y122834
X657480
X648032Y122835
X651181Y122834
X640500Y125000
X654331Y125984
X657480
Y129134
X648032
X654330
Y132283
X657481Y132284
X651181Y132283
X635852Y133715
X654330Y135433
X651181
X648032Y135434
X654330Y138582
Y141732
X651181
X648057Y141721
X637952Y142515
X651181Y144882
X654330
Y148031
X657480Y151219
X654330Y151181
X651181
X648059Y151191
X644882Y154331
X651181Y154330
X654330
X657480
X640775Y156218
X648031Y157480
X644882
X651181
X654330
X648031Y163779
X654330
X634169Y166500
X651181Y166929
X639108Y167800
X654330Y170078
X648031
X644882
X637343Y171335
X654330Y173228
X644882
X637343Y174835
X644882Y176378
X654330Y176377
X640509Y177600
X654330Y179526
X640931Y181102
X654330Y182676
Y185826
X651181Y188976
X657480Y192125
X651181
X640584Y194127
X632363Y209944
X640363
X636363
X646594Y210875
X638479Y230640
X634000Y234200
X630000
X633800Y239600
Y245700
X634100Y252000
X644153Y278745
X632750Y292195
Y295641
X634000Y306300
X631800Y316137
X632750Y330854
Y334300
X632900Y344950
X637500Y362400
X657673Y365400
X637500Y365900
X631140Y381353
X653007Y382828
X653360Y386210
X642900Y395400
X645970Y399130
X654770Y401166
X658601Y401800
X633676Y460080
X630000Y464900
X634050Y469200
X671640Y454410
X678700Y440950
X672800Y438832
X683250Y437813
X667414Y431956
X681540Y429640
X685750Y419460
X673900Y418880
X674150Y415380
X675031Y389383
X669031Y388383
X665031
X687150Y385550
X680300Y384900
X672281Y378883
X680700Y378200
X662306Y365477
X669450Y284900
X669125Y280405
X660400Y271900
X674841Y262854
X663100Y252700
X663000Y249200
X668600Y242800
X686900Y240354
X682700
X678500Y240324
X663200Y238100
X663400Y234100
X667353Y233486
X674023Y213815
X679400Y213300
X683913Y213313
X674172Y210095
X679452Y209815
X686352Y207200
X676377Y204723
Y201574
X685826
X679527Y198424
X685826
X660630Y198425
X676377Y198424
X670078Y192125
X666929
X676379Y192126
X682677Y192125
X660629
X663779
X685826
X688976
X682676Y188975
X679527
X682676Y185826
X676379Y182678
X663778Y182676
X670080Y182678
X682677Y182677
X679527Y182679
X682676Y179526
X663778
Y176377
X685826Y173228
X660629Y173227
X663778
X673229Y173228
X682677
X670078Y173227
X679527Y173229
X688976Y173228
X663778Y170078
X670078
X660629
X673229Y170079
Y166929
X685826
X682677
X663778Y166928
X688976Y166929
X679527
X670078Y166928
X679527Y163779
Y160629
X660630Y160630
X685826Y160629
X688976
X663778
X682677Y160630
X673227Y157479
X670078Y157480
X663778Y154330
X688976
X679527
X670078
X682677
X685826
X670078Y151181
X663779
X666929Y148031
X673228
X670080Y148030
X685826Y148031
X688976
X679527
X682677
X679526Y144880
X673227
X663778Y144883
X660629
Y141732
X673227Y138581
X660629Y138584
X679526Y138581
X666928
X685825
X663778Y138584
Y135431
X688978Y135435
X676379
X682679
X670116Y132283
X663779
X676376Y132281
X666929Y129134
X670079Y125985
X666929Y125984
X688977Y125985
X679528
X676378
X682678
X673229
X663780
X685827
X666929Y119685
X676378Y119686
X685827Y116535
X660629Y116536
X666929Y116535
X676377Y116536
X688976Y113385
X689049Y109487
X678189Y108784
X669500Y108400
X670146Y98505
X678225Y98496
X686279Y98494
X662047Y98539
X670146Y94505
X662047Y94539
X686279Y94494
X678225Y94496
X670146Y91005
X686279Y90994
X662047Y91039
X678225Y90996
X662047Y87039
X670146Y87005
X686279Y86994
X678225Y86996
X668100Y56100
X664301Y49998
X667900Y40800
X664301Y40104
X667149Y23411
X660200Y20200
X702391Y87010
X694365Y86958
X710378Y88899
X694365Y90958
X702391Y91010
X710378Y92899
X694365Y94458
X702391Y94510
X710378Y96399
X694365Y98458
X702391Y98510
X710378Y100399
X710517Y106823
X719010Y107281
X704849Y107385
X699563Y108815
X717197Y109646
X707649Y110002
X698425Y116535
X707874
X717322
X704725Y116536
X714173Y116535
X711023
X701575Y116536
X707874Y122835
X698426
X717322Y122834
X701575Y122835
X714173Y122834
X704725Y122835
X711023Y122834
X692126Y125984
X707873Y129133
X704723
X714172
X698425Y129134
X717322Y129133
X692148Y129119
X711022Y129133
X701574
X704724Y132283
X711023
X701575Y135433
X698425
X692124Y135431
X695274
X704725Y135434
X701574Y138582
X692125
X698425
X714173Y141732
X707874
X711023
X698425
X692126
X717322Y141731
X714172Y144880
X717322
X695275Y148031
X701574
X707873
X704724
X692126
X698425
X714172Y151180
X717322
X704724Y154330
X701574
X698425
X695275
X707873
X692126
X717322Y157479
X714172
X704724Y160629
X701574
X692126
X695275
X698425
X707873
X714172Y163778
X717322
X704724Y166929
X698425
X701574
X692126
X695275
X707873
X717322Y166928
X692126Y173228
X714172Y173227
X707873Y173228
X698425
X695275
X711023
X704724
X701574
X701575Y179527
X711022Y179526
X692126Y179527
X714172Y179526
X692126Y182676
X717322
X701575
X711022
Y185825
X701575Y185827
X692126
X711024Y188976
X701574Y192125
X711024
X714173
X707873
X692125
X704724
X698425
X692125Y198423
X707873Y198424
X714173Y198425
X701574Y198424
X704724Y198425
X695275
X717322
X711023
X714173Y201574
X704724
X718330Y205172
X706737Y205505
X711310Y207023
X697069Y207157
X705336Y208437
X715467Y210507
X697149Y219742
X692949
X714620Y221041
X695600Y240354
X691100
X712720Y240976
X695600Y244354
X704708Y252647
Y256647
Y260647
X695375Y260875
X704708Y264647
X695383Y266855
X707574Y276558
X695625Y282250
X693500Y373300
X700200Y384800
Y388200
X694765Y406915
X705320Y420610
X700855Y426719
X692200Y428700
X719920Y429700
X701120Y430620
X710200Y441200
X706120Y441410
X696950Y441400
X718110Y442960
X708355Y454712
X740900Y456400
X729870Y451300
X743480Y439080
X735570Y424760
X721380Y423930
X739680Y423900
X731300Y287611
X735300
X739300
X731318Y283571
X735318
X739318
X731155Y279636
X734638Y275696
X749620Y273620
X743507Y251685
X747558Y247274
X726656Y235244
X730737Y235199
X743460Y231900
X743200Y227900
X724465Y224741
X730694Y224473
X722523Y221315
X725009Y213292
X733565Y210184
X724776Y209963
X729246Y209941
X720819Y209800
X736272Y208181
X720357Y207104
X729136Y206654
X731915Y206310
X738839Y206080
X737832Y202664
X745485Y201673
X739752Y199615
X723621Y198424
X720471
X745485Y197673
X739852Y195915
X744052Y193784
X723621Y192125
X726770Y192126
X729920
X720472Y192125
X738416Y190551
X729920Y188977
X743752Y187115
X726770Y185827
X723621Y185826
X720437Y185829
X729920Y185827
X738952Y184215
X742502Y182715
X729920Y182678
X740352Y180115
X723621Y179527
X729921
X726770Y179528
X720472Y179527
X733070
X737315Y177952
X742252Y177015
X729920Y176378
X738352Y174615
X726770Y173229
X720472Y173228
X723621
X729920Y173229
X741952Y173115
X736219Y170079
X733070
X726770Y166930
X720471Y166928
X723621Y166929
X733069Y166930
X726771Y163779
X729921
X723621Y160629
X729921
X720472
X741077Y159790
X746750Y157700
X729921Y157480
Y154330
X720472
X723621
X743452Y151815
X729921Y148031
X720472
X723621
X737352Y145885
X729921Y144882
X723621Y141732
X729921
X720472
X729921Y138582
X739622Y137008
X729921Y135433
X720472
X723621
X741754Y134617
X729921Y132283
X723621Y129133
X729921Y129134
X737702Y128565
X740952Y126815
X729921Y125984
X726771Y122835
X729921Y122834
X720472
X723622
X739952Y120649
X720473Y116536
X723622Y116535
X743100Y114700
X736785Y110185
X734212Y109995
X726100Y107200
X734709Y106595
X737800Y106525
X731000Y106315
X722673Y105444
X725943Y100147
X745100Y97500
X720744Y92427
X725295Y88609
X728788Y88540
X744833Y78995
X747919Y76667
X763560Y59820
X750773Y74636
X767359Y82076
X772107Y83046
X754528Y83228
X754572Y86923
X761650Y89937
X771610Y93040
X752853Y100900
X768250Y106300
X768100Y109700
X773000Y119600
X776600
X768700Y129800
X768900Y134800
X750550Y135200
X765200Y135750
X764600Y141500
X757471Y148193
X763050Y154100
X761400Y160050
X758050Y164050
X769600Y164200
X760800Y169550
X760600Y173700
X779200Y178650
X764750Y179300
X761550Y180500
X764550Y182900
X760715Y197200
Y201700
Y210200
Y214200
X759558Y241027
Y247274
X761484Y251581
X774637Y251876
X751693Y255540
X761484Y255581
X765638Y255635
X774657Y255999
X751693Y259540
X755693
X761638Y259635
X774637Y259746
Y263746
X770637Y267746
X774637
X767890Y273380
X753560Y273780
X751878Y276817
X775486Y287316
X763292Y287630
X754227Y297611
Y301111
X751133Y313984
X765764Y326844
X776497Y338392
X761520Y339110
X775672Y350204
X786610Y321340
X782770Y321200
X786300Y309900
X801728Y304572
X801853Y300515
X793912Y297020
X793837Y291696
Y287696
Y283696
X786006Y283383
X781640Y282160
X793837Y279636
X781640Y278660
X793837Y275696
X780837Y271761
X784837
X793837
X780837Y267826
X784837
X793837
X784837Y263891
X805254Y263886
X793837Y263696
X784837Y259951
X793852Y256011
Y252076
X795498Y246171
X780837Y240885
X790714Y237308
X790000Y224700
X801618Y214116
Y210116
X800612Y185432
X804412Y185332
X786400Y179000
X804400Y175000
X785000Y158900
X794500Y134283
X804320Y134300
X786500Y134283
X782500
X799500Y106000
X799493Y93250
X781000Y88000
X788287Y86087
X781000Y84200
X799250Y71125
T03
X49900Y209700
X54900Y214700
Y209700
X59900
X54900Y204700
X175800Y129500
X179800
Y133500
X175800
X196900Y174400
X192400
Y178700
X196900
X192400Y183000
X196900
X192400Y187300
X196900
Y191600
X192400
X201400Y174400
Y178700
Y183000
Y187300
Y191600
X242620Y390670
X246220
X249820
X247620Y395170
X243120
X246493Y399567
X242893
X253693
X250093
X257293
X251870Y395170
X256120
X257020Y390670
X253420
X260620
Y395170
X260893Y399567
X599503Y447123
Y450723
Y454323
Y457923
Y461523
Y465123
X609400Y464850
X604400
X609400Y461250
X604400Y460350
X609400Y457650
X604400Y456100
X609400Y454050
X604400Y451850
X609400Y450450
X604400Y447350
X609400Y446850
X689900Y452950
Y457400
X689700Y461850
X694400Y461900
X698950Y461800
X694400Y457400
X698900
X699000Y452950
X694400Y452900
T04
X338583Y10651
X352756
X366929
X381103
X395276
X409449
X423622
X437796
X451969
X466142
X480315
X494488
X508661
X522835
X537008
X551181
X565354
X579527
X708661
X722834
X737007
X751181
X410236Y404331
Y419291
Y434252
Y449212
T05
X338583Y53150
Y48819
Y43307
Y38977
Y34646
Y29134
Y24804
Y20473
Y14961
X345670Y5906
Y10237
Y15748
Y20079
Y24410
Y29922
Y34252
Y38583
Y44095
Y48426
X352756Y53150
Y48819
X359843Y48426
Y44095
X352756Y43307
Y38977
X359843Y38583
X352756Y34646
X359843Y34252
Y29922
X352756Y29134
Y24804
X359843Y24410
X352756Y20473
X359843Y20079
Y15748
X352756Y14961
X359843Y10237
Y5906
X366929Y14961
Y20473
Y24804
Y29134
Y34646
Y38977
Y43307
Y48819
Y53150
X374016Y48426
Y44095
Y38583
Y34252
Y29922
Y24410
Y20079
Y15748
Y10237
Y5906
X388189
Y10237
X381103Y14961
X388189Y15748
Y20079
X381103Y20473
X388189Y24410
X381103Y24804
Y29134
X388189Y29922
Y34252
X381103Y34646
X388189Y38583
X381103Y38977
Y43307
X388189Y44095
Y48426
X381103Y48819
Y53150
X395276
Y48819
Y43307
Y38977
Y34646
Y29134
Y24804
Y20473
Y14961
X402363Y5906
Y10237
X409449Y14961
X402363Y15748
Y20079
X409449Y20473
X402363Y24410
X409449Y24804
Y29134
X402363Y29922
Y34252
X409449Y34646
X402363Y38583
X409449Y38977
Y43307
X402363Y44095
Y48426
X409449Y48819
Y53150
X416536Y48426
Y44095
Y38583
Y34252
Y29922
Y24410
Y20079
Y15748
Y10237
Y5906
X423622Y14961
Y20473
Y24804
Y29134
Y34646
Y38977
Y43307
Y48819
Y53150
X437796
Y48819
X430709Y48426
Y44095
X437796Y43307
Y38977
X430709Y38583
X437796Y34646
X430709Y34252
Y29922
X437796Y29134
Y24804
X430709Y24410
X437796Y20473
X430709Y20079
Y15748
X437796Y14961
X430709Y10237
Y5906
X444882
Y10237
Y15748
Y20079
Y24410
Y29922
Y34252
Y38583
Y44095
Y48426
X451969Y53150
Y48819
X459055Y48426
Y44095
X451969Y43307
Y38977
X459055Y38583
X451969Y34646
X459055Y34252
Y29922
X451969Y29134
Y24804
X459055Y24410
X451969Y20473
X459055Y20079
Y15748
X451969Y14961
X459055Y10237
Y5906
X466142Y14961
Y20473
Y24804
Y29134
Y34646
Y38977
Y43307
Y48819
Y53150
X473229Y48426
Y44095
Y38583
Y34252
Y29922
Y24410
Y20079
Y15748
Y10237
Y5906
X487402
Y10237
X480315Y14961
X487402Y15748
Y20079
X480315Y20473
X487402Y24410
X480315Y24804
Y29134
X487402Y29922
Y34252
X480315Y34646
X487402Y38583
X480315Y38977
Y43307
X487402Y44095
Y48426
X480315Y48819
Y53150
X494489
Y48819
Y43307
Y38977
Y34646
Y29134
Y24804
Y20473
Y14961
X501575Y5906
Y10237
X508662Y14961
X501575Y15748
Y20079
X508662Y20473
X501575Y24410
X508662Y24804
Y29134
X501575Y29922
Y34252
X508662Y34646
X501575Y38583
X508662Y38977
Y43307
X501575Y44095
Y48426
X508662Y48819
Y53150
X515748Y48426
Y44095
Y38583
Y34252
Y29922
Y24410
Y20079
Y15748
Y10237
Y5906
X529922
Y10237
X522835Y14961
X529922Y15748
Y20079
X522835Y20473
X529922Y24410
X522835Y24804
Y29134
X529922Y29922
Y34252
X522835Y34646
X529922Y38583
X522835Y38977
Y43307
X529922Y44095
Y48426
X522835Y48819
Y53150
X537008
Y48819
Y43307
Y38977
Y34646
Y29134
Y24804
Y20473
Y14961
X544095Y5906
Y10237
Y15748
Y20079
Y24410
Y29922
Y34252
Y38583
Y44095
Y48426
X551181Y53150
Y48819
X558268Y48426
Y44095
X551181Y43307
Y38977
X558268Y38583
X551181Y34646
X558268Y34252
Y29922
X551181Y29134
Y24804
X558268Y24410
X551181Y20473
X558268Y20079
Y15748
X551181Y14961
X558268Y10237
Y5906
X565355Y14961
Y20473
Y24804
Y29134
Y34646
Y38977
Y43307
Y48819
Y53150
X579528
Y48819
X572441Y48426
Y44095
X579528Y43307
Y38977
X572441Y38583
X579528Y34646
X572441Y34252
Y29922
X579528Y29134
Y24804
X572441Y24410
X579528Y20473
X572441Y20079
Y15748
X579528Y14961
X572441Y10237
Y5906
X586614
Y10237
Y15748
Y20079
Y24410
Y29922
Y34252
Y38583
Y44095
Y48426
X708661Y53150
Y48819
Y43307
Y38977
Y34646
Y29134
Y24804
Y20473
Y14961
X715748Y5906
Y10237
Y15748
Y20079
Y24410
Y29922
Y34252
Y38583
Y44095
Y48426
X722834Y53150
Y48819
X729921Y48426
Y44095
X722834Y43307
Y38977
X729921Y38583
X722834Y34646
X729921Y34252
Y29922
X722834Y29134
Y24804
X729921Y24410
X722834Y20473
X729921Y20079
Y15748
X722834Y14961
X729921Y10237
Y5906
X737007Y14961
Y20473
Y24804
Y29134
Y34646
Y38977
Y43307
Y48819
Y53150
X744094Y48426
Y44095
Y38583
Y34252
Y29922
Y24410
Y20079
Y15748
Y10237
Y5906
X758267
Y10237
X751181Y14961
X758267Y15748
Y20079
X751181Y20473
X758267Y24410
X751181Y24804
Y29134
X758267Y29922
Y34252
X751181Y34646
X758267Y38583
X751181Y38977
Y43307
X758267Y44095
Y48426
X751181Y48819
Y53150
T06
X407480Y407284
X416339
X425197
X422244Y412795
X419292Y410039
X413386Y412795
X410433Y410039
X404528Y412795
X401575Y410039
Y425000
X404528Y427756
X407480Y422244
X410433Y425000
X413386Y427756
X416339Y422244
X419292Y425000
X422244Y427756
X425197Y422244
Y437205
X416339
X407480
X401575Y439961
X404528Y442717
X410433Y439961
X413386Y442717
X419292Y439961
X422244Y442717
X425197Y452165
X422244Y457677
X419292Y454921
X416339Y452165
X413386Y457677
X410433Y454921
X407480Y452165
X404528Y457677
X401575Y454921
T07
X10364Y5500
X65364
X60364
X55364
X50364
X45364
X25364
X15364
X40364
X35364
X30364
X20364
X5500Y10384
Y15384
Y20384
Y25384
Y30384
Y35384
Y40384
Y45384
Y50384
Y55384
Y60384
Y65384
Y70384
Y75384
Y80384
Y85384
Y90384
Y95384
Y100384
Y105384
Y110384
Y115384
Y120384
Y125384
Y130384
Y135384
Y140384
Y145384
Y150384
Y155384
Y160384
Y165384
Y170384
Y175384
Y180384
Y185384
Y190384
Y195384
Y200384
Y205384
Y210384
Y215384
Y220384
Y225384
Y230384
Y235384
Y240384
Y245384
Y250384
Y255384
Y260384
Y265384
Y270384
Y275384
Y280384
Y285384
Y290384
Y295384
Y300384
Y305384
Y310384
Y315384
Y320384
Y325384
Y330384
Y335384
Y340384
Y345384
Y350384
Y355384
Y360384
Y365384
Y370384
Y375384
Y380384
Y385384
Y390384
Y395384
Y400384
Y405384
Y410384
Y415384
Y420384
Y425384
Y430384
Y435384
Y440384
Y445384
Y450384
Y455384
Y460384
Y465384
Y470384
Y475384
Y480384
Y485384
Y490384
Y495384
Y500384
Y505384
Y510384
Y515384
Y520384
Y525384
Y530384
Y535384
Y540384
Y545384
Y550384
Y555384
Y560384
X55266Y565366
X65266
X60266
X35266
X20266
X15266
X45266
X10266
X30266
X40266
X50266
X25266
X100266
X70266
X95266
X90266
X85266
X135266
X130266
X75266
X125266
X120266
X115266
X110266
X105266
X80266
X94080Y448470
X123200Y175800
X128459Y175658
X122984Y170984
X128580Y170810
X125741Y166309
X93619Y111166
X99619
X105619
X75119
X87619
X81119
X75364Y5500
X70364
X85364
X80364
X90364
X95364
X170364
X195364
X190364
X180364
X205364
X185364
X175364
X200364
X198557Y153196
X161100Y160500
X151500
X156300
X165900
X170900
X197630Y160900
X192830
X202430
Y165700
X192830
X197630
X192830Y170500
X202430
X197630
X191900Y196100
X196900
X201700
X196900Y200900
X191900
X201700
X178450Y203150
X170900Y205000
X156300
X161100
X144800Y204950
X140000
X165900Y205000
X151500
X196900Y205700
X191900
X201700
X191900Y210500
X196900
X177850Y324800
X197718Y350937
X169995Y353588
X174995
X197718Y355859
X169995Y358388
X165195
X174995
X158067Y378857
X160550Y414100
X143608Y415900
X177468Y417900
X157650Y418100
X160400Y422900
X142865Y424021
X177532Y426134
X160400Y427700
X142991Y430900
X160400Y432500
X177421Y432909
X145456Y440338
X176423Y440472
X145392Y445207
X176311Y445493
X208900Y448450
X203000Y451300
X204252Y470198
X209052
X204364Y478917
X209164
X208589Y489694
X145266Y565366
X200266
X140266
X160266
X165266
X190266
X150266
X170266
X185266
X205266
X195266
X180266
X175266
X155266
X240266
X220266
X255266
X215266
X210266
X225266
X235266
X265266
X245266
X270266
X230266
X275266
X250266
X260266
X212589Y494694
X220589
X216589Y489694
X224589
X213700Y448450
X246700Y418600
X276070Y395357
X223000Y378246
X222909Y371864
X222818Y364806
X254300Y357732
X266404Y249707
X268000Y244900
X249204Y244103
X227260Y240264
X222460
X268000Y240100
X222490Y235373
X227290
X268000Y235300
X253600Y230500
X268000
X258400
X263200
X222246Y229952
X227046
X268000Y225700
X263200
X258400
X253600
X222800Y223800
X227600
X253600Y220900
X268000
X263200
X258400
X222800Y219000
X227600
X268000Y216000
X227600Y214200
X222800
X268000Y211200
X222800Y209400
X227600
X268000Y206400
X222800Y204600
X227600
X268000Y201600
Y196800
X268118Y191305
X268064Y184062
X268000Y178062
X272800Y177600
Y172800
X268064Y171792
X272800Y168000
X268000Y165962
X227500Y158900
X222700
X268000Y158700
X227500Y154100
X222700
X268000Y153900
X251800Y153600
X222700Y149300
X227500
X268000Y149100
X251800Y148800
X227500Y144500
X222700
X268000Y144300
X251800Y144000
X227500Y139700
X222700
X258400Y139500
X263200
X253600
X268000
X258400Y134700
X253600
X272800
X263200
X268000
X255364Y5500
X275364
X270364
X265364
X210364
X215364
X235364
X220364
X225364
X230364
X250364
X260364
X245364
X240364
X320364
X285364
X325364
X330364
X290364
X315364
X295364
X300364
X280364
X305364
X310364
X287000Y117600
Y125000
X285500Y130400
X295100
X290300
X295960Y148987
Y154387
X308907Y161000
Y166400
X295650Y169554
X308907Y171800
X287300Y173000
X292100
X308907Y177200
Y182800
Y188200
X296200Y190500
X308907Y193600
X296200Y195900
X308907Y199000
Y204400
Y209800
X295801Y210294
X287800Y214500
X292600
X308907Y215200
Y220600
Y226000
Y231400
X296400Y232550
X308907Y236800
X296400Y237950
X308907Y242200
X286279Y255540
X295879
X291079
X346700Y291533
Y296333
X329156Y515492
Y520492
Y525492
Y530492
Y535492
Y540492
Y545492
Y550492
Y555492
Y560492
X300266Y565366
X310266
X305266
X325266
X315266
X295266
X280266
X290266
X285266
X320266
X350586Y495815
X355523Y495025
X360461Y494236
X365398Y493446
X370335Y492656
X375272Y491866
X380210Y491077
X390169Y490563
X400169
X415169
X410169
X405169
X385169
X395169
X430169
X435169
X440169
X420169
X425169
X445146Y490850
X450083Y491640
X455020Y492430
X459958Y493219
X464895Y494009
X469832Y494799
X474769Y495589
X522942Y425481
X527742
X518142
Y432481
X527742
X522942
X545900Y437800
X551400
X539800Y437900
X509500Y441200
Y446000
Y450800
X505500Y464400
Y469200
X529500Y471500
X505500Y474000
X497636Y515532
Y520532
Y525532
Y530532
Y535532
Y540532
Y545532
Y550532
Y555532
Y560532
X507550Y565366
X552550
X542550
X502550
X532550
X512550
X557550
X522550
X527550
X537550
X517550
X547550
X622550
X627550
X617550
X587550
X582550
X577550
X572550
X567550
X592550
X597550
X612550
X602550
X607550
X562550
X605534Y480027
X619600Y446100
X629200
X624400
X613713Y428617
X623313
X618513
X628113
X571300Y414800
X580900
X576100
X567200Y407700
X576862Y384378
X581692
X572062
X581087Y379569
X576287
X575134Y298026
X570234
X580034
X572634Y293526
X577534
X582554Y116361
X576797Y113877
X591446Y6545
X616446
X626446
X621446
X611446
X606446
X601446
X596446
X631446
X666446
X641446
X696446
X691446
X661446
X686446
X651446
X646446
X681446
X656446
X676446
X671446
X636446
X655964Y52248
X675136Y268500
X637705Y298765
X642705
X637705Y303765
X642705
X674700Y306300
X679500
X660100Y307500
X654642Y307707
X665520
X674700Y311100
X679500
X654642Y312507
X665520
X674700Y315900
X679500
X654488Y317417
X665478Y317527
X659977Y323082
X664731Y324099
X659977Y327882
X664731Y328899
X659977Y332682
X664731Y333699
X659977Y337482
X696900Y337800
X664731Y338499
X659977Y342282
X664731Y343299
X659977Y347082
X660115Y351977
Y356777
X697500Y358200
X655500Y360000
X660115Y361577
X637550Y389050
X632150Y389100
X684400Y400100
X653200Y408800
X653032Y420245
X658032
X655532Y425245
X635000Y427784
X659000Y428900
X652200Y429100
X639120Y462230
X675700Y463500
Y468000
X675400Y472300
X694950Y473050
Y477850
X688500Y484400
Y488600
X652550Y565366
X677550
X697550
X692550
X647550
X642550
X632550
X687550
X682550
X637550
X672550
X667550
X662550
X657550
X712550
X702550
X722550
X727550
X732550
X707550
X767550
X762550
X757550
X717550
X752550
X737550
X747550
X742550
X724400Y490200
Y485200
Y480400
X705400Y477400
X740900Y476400
X724400Y475600
X740900Y469400
X704340Y468062
X724422Y464139
X740900Y461900
X725247Y458974
X704115Y414466
Y409666
Y404866
Y400066
X711000Y395100
X706000
X705900Y386900
X710900Y386800
X728700Y381000
X742200Y380400
X728700Y376200
X742200Y375600
X728700Y371400
X742200Y370800
X722100Y368300
X717300
X712500
Y363500
X722100
X717300
X707100Y358200
X702300
X732600Y355200
Y350400
X714600Y348500
X709800
X742200Y345600
X737400
X732600
X709800Y343700
X714600
X742200Y340800
X732600
X737400
X714600Y338900
X706500Y337800
X701700
X732600Y336000
Y331200
X701100Y315900
X705900
Y311100
X701100
X705900Y306300
X701100
X701446Y6545
X765364Y5500
X810364
X805364
X800364
X775364
X780364
X795364
X785364
X770364
X790364
X815364
X821272Y9340
Y14340
Y19340
Y24340
Y29340
Y34340
Y39340
Y44340
Y49340
Y54340
Y59340
Y64340
Y69340
Y74340
Y79340
Y84340
Y89340
Y94340
Y99340
Y104340
Y109340
Y114340
Y119340
Y124340
Y129340
Y134340
Y139340
Y144340
Y149340
Y154340
Y159340
Y164340
Y169340
Y174340
Y179340
Y184340
Y189340
Y194340
Y199340
Y204340
Y209340
X771083Y211784
X821272Y214340
Y219340
Y224340
Y229340
Y234340
Y239340
Y244340
Y249340
Y254340
Y259340
Y264340
Y269340
Y274340
Y279340
Y284340
Y289340
Y294340
Y299340
Y304340
Y309340
Y314340
Y319340
Y324340
Y329340
Y334340
Y339340
Y344340
Y349340
Y354340
Y359340
Y364340
Y369340
Y374340
Y379340
Y384340
Y389340
Y394340
Y399340
Y404340
Y409340
Y414340
Y419340
Y424340
Y429340
Y434340
Y439340
Y444340
Y449340
Y454340
Y459340
Y464340
Y469340
Y474340
Y479340
Y484340
Y489340
Y494340
Y499340
Y504340
Y509340
Y514340
Y519340
Y524340
Y529340
Y534340
Y539340
Y544340
Y549340
Y554340
Y559340
X787550Y565366
X782550
X777550
X772550
X797550
X792550
X802550
X817550
X807550
X812550
T08
X108672Y132871
Y138471
X102672
Y132871
X96672Y138471
Y132871
X90672Y138471
Y132871
X84672
Y138471
X49302Y155919
Y150519
X43902
Y155919
X38502
Y150519
Y161319
X43902
X49302
T09
X145669Y19803
Y25708
Y31614
Y41456
Y47362
Y53267
X158267
Y47362
Y41456
Y31614
Y25708
Y19803
T10
X37402Y499724
X789370
T11
X37402Y535158
X789370
T12
X295275Y531496
X531495
T13
X37402Y517441
X789370
T14
X98425Y472441
X137795
T15
X15812Y-86244
X27058Y25484
X81539Y542850
X411652Y539991
X798456Y26432
X812711Y-86834
T16
X389764Y460630
X437008
T17
X116063Y14567
T18
X116063Y39075
T19
X374015Y156220
X596456Y116142
X781496Y198818
X531496Y371299
M30
